# T6G (Grand Teton) — schematic netlist excerpt (pin names and nets, part order shuffled) for the footprints in the layout excerpt that follows; sources: Cadence DE-HDL packaged netlist, KiCad conversion of 04192023_DAF0TMB3IC0_F0TG_MB_C_brd_V02_OCP.brd

R4136  Q_RES  100K 1% EMPTY  pkg 0402LF  page 125 : A = PRSNT_CABLE_GPU_A2_N ; B = GND
C2442  Q_CAP  22UF 4V 20% X6S  pkg C0402  page 74 : A = PVDDCR_SOC_P1 ; B = GND

(kicad_pcb
	(version 20260206)
	(generator "pcbnew")
	(generator_version "10.0")
	(general
		(thickness 1.6)
		(legacy_teardrops no)
	)
	(paper "A4")
	(title_block
		(title "04192023_DAF0TMB3IC0_F0TG_MB_C_brd_V02_OCP.brd")
		(comment 1 "Grand Teton / footprints 1728-1729 of 8354")
	)
	(layers
		(0 "F.Cu" signal "TOP")
		(4 "In1.Cu" signal "GND")
		(6 "In2.Cu" signal "IN1")
		(8 "In3.Cu" signal "GND1")
		(10 "In4.Cu" signal "IN2")
		(12 "In5.Cu" signal "GND2")
		(14 "In6.Cu" signal "IN3")
		(16 "In7.Cu" signal "GND3")
		(18 "In8.Cu" signal "VCC")
		(20 "In9.Cu" signal "VCC1")
		(22 "In10.Cu" signal "GND4")
		(24 "In11.Cu" signal "IN4")
		(26 "In12.Cu" signal "GND5")
		(28 "In13.Cu" signal "IN5")
		(30 "In14.Cu" signal "GND6")
		(32 "In15.Cu" signal "IN6")
		(34 "In16.Cu" signal "GND7")
		(2 "B.Cu" signal "BOTTOM")
		(9 "F.Adhes" user "F.Adhesive")
		(11 "B.Adhes" user "B.Adhesive")
		(13 "F.Paste" user "Package Geometry/Pastemask Top")
		(15 "B.Paste" user "Package Geometry/Pastemask Bottom")
		(5 "F.SilkS" user "Ref Des/Silkscreen Top")
		(7 "B.SilkS" user "Ref Des/Silkscreen Bottom")
		(1 "F.Mask" user "Board Geometry/Soldermask Top")
		(3 "B.Mask" user "Board Geometry/Soldermask Bottom")
		(17 "Dwgs.User" user "User.Drawings")
		(19 "Cmts.User" user "User.Comments")
		(21 "Eco1.User" user "User.Eco1")
		(23 "Eco2.User" user "User.Eco2")
		(25 "Edge.Cuts" user "Board Geometry/Outline")
		(27 "Margin" user)
		(31 "F.CrtYd" user "Package Geometry/Place Bound Top")
		(29 "B.CrtYd" user "Package Geometry/Place Bound Bottom")
		(35 "F.Fab" user "Ref Des/Assembly Top")
		(33 "B.Fab" user "Ref Des/Assembly Bottom")
	)
	(footprint ""
		(layer "F.Cu")
		(at 113.105946 -258.795266)
		(property "Reference" "C2442"
			(at 0 0 0)
			(layer "F.SilkS")
			(hide yes)
			(effects
				(font
					(size 1.27 1.27)
				)
			)
		)
		(property "Value" ""
			(at 0 0 0)
			(layer "F.Fab")
			(effects
				(font
					(size 1.27 1.27)
				)
			)
		)
		(duplicate_pad_numbers_are_jumpers no)
		(fp_line
			(start -0.7874 -0.4064)
			(end 0.7874 -0.4064)
			(stroke
				(width 0.1524)
				(type default)
			)
			(layer "F.SilkS")
		)
		(fp_line
			(start -0.7874 0.4064)
			(end -0.7874 -0.4064)
			(stroke
				(width 0.1524)
				(type default)
			)
			(layer "F.SilkS")
		)
		(fp_line
			(start 0.7874 -0.4064)
			(end 0.7874 0.4064)
			(stroke
				(width 0.1524)
				(type default)
			)
			(layer "F.SilkS")
		)
		(fp_line
			(start 0.7874 0.4064)
			(end -0.7874 0.4064)
			(stroke
				(width 0.1524)
				(type default)
			)
			(layer "F.SilkS")
		)
		(fp_line
			(start -0.67945 -0.305054)
			(end -0.12065 -0.305054)
			(stroke
				(width 0.1)
				(type default)
			)
			(layer "F.Fab")
		)
		(fp_line
			(start -0.67945 0.3048)
			(end -0.67945 -0.305054)
			(stroke
				(width 0.1)
				(type default)
			)
			(layer "F.Fab")
		)
		(fp_line
			(start -0.12065 -0.305054)
			(end -0.12065 -0.2794)
			(stroke
				(width 0.1)
				(type default)
			)
			(layer "F.Fab")
		)
		(fp_line
			(start -0.12065 -0.2794)
			(end 0.12065 -0.2794)
			(stroke
				(width 0.1)
				(type default)
			)
			(layer "F.Fab")
		)
		(fp_line
			(start -0.12065 0.2794)
			(end -0.12065 0.3048)
			(stroke
				(width 0.1)
				(type default)
			)
			(layer "F.Fab")
		)
		(fp_line
			(start -0.12065 0.3048)
			(end -0.67945 0.3048)
			(stroke
				(width 0.1)
				(type default)
			)
			(layer "F.Fab")
		)
		(fp_line
			(start 0.120396 0.2794)
			(end -0.12065 0.2794)
			(stroke
				(width 0.1)
				(type default)
			)
			(layer "F.Fab")
		)
		(fp_line
			(start 0.120396 0.3048)
			(end 0.120396 0.2794)
			(stroke
				(width 0.1)
				(type default)
			)
			(layer "F.Fab")
		)
		(fp_line
			(start 0.12065 -0.3048)
			(end 0.67945 -0.3048)
			(stroke
				(width 0.1)
				(type default)
			)
			(layer "F.Fab")
		)
		(fp_line
			(start 0.12065 -0.2794)
			(end 0.12065 -0.3048)
			(stroke
				(width 0.1)
				(type default)
			)
			(layer "F.Fab")
		)
		(fp_line
			(start 0.67945 -0.3048)
			(end 0.67945 0.3048)
			(stroke
				(width 0.1)
				(type default)
			)
			(layer "F.Fab")
		)
		(fp_line
			(start 0.67945 0.3048)
			(end 0.120396 0.3048)
			(stroke
				(width 0.1)
				(type default)
			)
			(layer "F.Fab")
		)
		(pad "1" smd circle
			(at -0.40005 0)
			(size 0 0)
			(layers "F.Cu" "F.Mask" "F.Paste")
			(net "PVDDCR_SOC_P1")
		)
		(pad "2" smd circle
			(at 0.40005 0)
			(size 0 0)
			(layers "F.Cu" "F.Mask" "F.Paste")
			(net "GND")
		)
	)
	(footprint ""
		(layer "F.Cu")
		(at 308.198266 -431.256186)
		(property "Reference" "R4136"
			(at 0 0 0)
			(layer "F.SilkS")
			(hide yes)
			(effects
				(font
					(size 1.27 1.27)
				)
			)
		)
		(property "Value" ""
			(at 0 0 0)
			(layer "F.Fab")
			(effects
				(font
					(size 1.27 1.27)
				)
			)
		)
		(duplicate_pad_numbers_are_jumpers no)
		(fp_line
			(start -0.7874 -0.4064)
			(end 0.7874 -0.4064)
			(stroke
				(width 0.1524)
				(type default)
			)
			(layer "F.SilkS")
		)
		(fp_line
			(start -0.7874 0.4064)
			(end -0.7874 -0.4064)
			(stroke
				(width 0.1524)
				(type default)
			)
			(layer "F.SilkS")
		)
		(fp_line
			(start 0.7874 -0.4064)
			(end 0.7874 0.4064)
			(stroke
				(width 0.1524)
				(type default)
			)
			(layer "F.SilkS")
		)
		(fp_line
			(start 0.7874 0.4064)
			(end -0.7874 0.4064)
			(stroke
				(width 0.1524)
				(type default)
			)
			(layer "F.SilkS")
		)
		(fp_line
			(start -0.67945 -0.305054)
			(end -0.12065 -0.305054)
			(stroke
				(width 0.1)
				(type default)
			)
			(layer "F.Fab")
		)
		(fp_line
			(start -0.67945 0.3048)
			(end -0.67945 -0.305054)
			(stroke
				(width 0.1)
				(type default)
			)
			(layer "F.Fab")
		)
		(fp_line
			(start -0.12065 -0.305054)
			(end -0.12065 -0.2794)
			(stroke
				(width 0.1)
				(type default)
			)
			(layer "F.Fab")
		)
		(fp_line
			(start -0.12065 -0.2794)
			(end 0.12065 -0.2794)
			(stroke
				(width 0.1)
				(type default)
			)
			(layer "F.Fab")
		)
		(fp_line
			(start -0.12065 0.2794)
			(end -0.12065 0.3048)
			(stroke
				(width 0.1)
				(type default)
			)
			(layer "F.Fab")
		)
		(fp_line
			(start -0.12065 0.3048)
			(end -0.67945 0.3048)
			(stroke
				(width 0.1)
				(type default)
			)
			(layer "F.Fab")
		)
		(fp_line
			(start 0.120396 0.2794)
			(end -0.12065 0.2794)
			(stroke
				(width 0.1)
				(type default)
			)
			(layer "F.Fab")
		)
		(fp_line
			(start 0.120396 0.3048)
			(end 0.120396 0.2794)
			(stroke
				(width 0.1)
				(type default)
			)
			(layer "F.Fab")
		)
		(fp_line
			(start 0.12065 -0.3048)
			(end 0.67945 -0.3048)
			(stroke
				(width 0.1)
				(type default)
			)
			(layer "F.Fab")
		)
		(fp_line
			(start 0.12065 -0.2794)
			(end 0.12065 -0.3048)
			(stroke
				(width 0.1)
				(type default)
			)
			(layer "F.Fab")
		)
		(fp_line
			(start 0.67945 -0.3048)
			(end 0.67945 0.3048)
			(stroke
				(width 0.1)
				(type default)
			)
			(layer "F.Fab")
		)
		(fp_line
			(start 0.67945 0.3048)
			(end 0.120396 0.3048)
			(stroke
				(width 0.1)
				(type default)
			)
			(layer "F.Fab")
		)
		(pad "1" smd circle
			(at -0.40005 0)
			(size 0 0)
			(layers "F.Cu" "F.Mask" "F.Paste")
			(net "PRSNT_CABLE_GPU_A2_N")
		)
		(pad "2" smd circle
			(at 0.40005 0)
			(size 0 0)
			(layers "F.Cu" "F.Mask" "F.Paste")
			(net "GND")
		)
	)
)
